(kicad_pcb
	(version 20260206)
	(generator "pcbnew")
	(generator_version "10.0")
	(general
		(thickness 1.6)
		(legacy_teardrops no)
	)
	(paper "A4")
	(title_block
		(title "03242023_DA0F0TMBIJ0_F0T_Motherboard_J_brd_V01_OCP.brd")
		(comment 1 "Grand Teton / footprints 2841-2847 of 6105")
	)
	(layers
		(0 "F.Cu" signal "TOP")
		(4 "In1.Cu" signal "GND")
		(6 "In2.Cu" signal "IN1")
		(8 "In3.Cu" signal "GND1")
		(10 "In4.Cu" signal "IN2")
		(12 "In5.Cu" signal "GND2")
		(14 "In6.Cu" signal "IN3")
		(16 "In7.Cu" signal "GND3")
		(18 "In8.Cu" signal "VCC")
		(20 "In9.Cu" signal "VCC1")
		(22 "In10.Cu" signal "GND4")
		(24 "In11.Cu" signal "IN4")
		(26 "In12.Cu" signal "GND5")
		(28 "In13.Cu" signal "IN5")
		(30 "In14.Cu" signal "GND6")
		(32 "In15.Cu" signal "IN6")
		(34 "In16.Cu" signal "GND7")
		(2 "B.Cu" signal "BOTTOM")
		(9 "F.Adhes" user "F.Adhesive")
		(11 "B.Adhes" user "B.Adhesive")
		(13 "F.Paste" user "Package Geometry/Pastemask Top")
		(15 "B.Paste" user "Package Geometry/Pastemask Bottom")
		(5 "F.SilkS" user "Ref Des/Silkscreen Top")
		(7 "B.SilkS" user "Ref Des/Silkscreen Bottom")
		(1 "F.Mask" user "Board Geometry/Soldermask Top")
		(3 "B.Mask" user "Board Geometry/Soldermask Bottom")
		(17 "Dwgs.User" user "User.Drawings")
		(19 "Cmts.User" user "User.Comments")
		(21 "Eco1.User" user "User.Eco1")
		(23 "Eco2.User" user "User.Eco2")
		(25 "Edge.Cuts" user "Board Geometry/Outline")
		(27 "Margin" user)
		(31 "F.CrtYd" user "Package Geometry/Place Bound Top")
		(29 "B.CrtYd" user "Package Geometry/Place Bound Bottom")
		(35 "F.Fab" user "Ref Des/Assembly Top")
		(33 "B.Fab" user "Ref Des/Assembly Bottom")
	)
	(footprint ""
		(layer "F.Cu")
		(at 131.50088 -100.167948 -90)
		(property "Reference" "R4413"
			(at 0 0 270)
			(layer "F.SilkS")
			(hide yes)
			(effects
				(font
					(size 1.27 1.27)
				)
			)
		)
		(property "Value" ""
			(at 0 0 270)
			(layer "F.Fab")
			(effects
				(font
					(size 1.27 1.27)
				)
			)
		)
		(duplicate_pad_numbers_are_jumpers no)
		(fp_line
			(start -0.7874 0.4064)
			(end -0.7874 -0.4064)
			(stroke
				(width 0.1524)
				(type default)
			)
			(layer "F.SilkS")
		)
		(fp_line
			(start 0.7874 0.4064)
			(end -0.7874 0.4064)
			(stroke
				(width 0.1524)
				(type default)
			)
			(layer "F.SilkS")
		)
		(fp_line
			(start -0.7874 -0.4064)
			(end 0.7874 -0.4064)
			(stroke
				(width 0.1524)
				(type default)
			)
			(layer "F.SilkS")
		)
		(fp_line
			(start 0.7874 -0.4064)
			(end 0.7874 0.4064)
			(stroke
				(width 0.1524)
				(type default)
			)
			(layer "F.SilkS")
		)
		(fp_line
			(start -0.67945 0.3048)
			(end -0.67945 -0.305054)
			(stroke
				(width 0.1)
				(type default)
			)
			(layer "F.Fab")
		)
		(fp_line
			(start -0.12065 0.3048)
			(end -0.67945 0.3048)
			(stroke
				(width 0.1)
				(type default)
			)
			(layer "F.Fab")
		)
		(fp_line
			(start 0.120396 0.3048)
			(end 0.120396 0.2794)
			(stroke
				(width 0.1)
				(type default)
			)
			(layer "F.Fab")
		)
		(fp_line
			(start 0.67945 0.3048)
			(end 0.120396 0.3048)
			(stroke
				(width 0.1)
				(type default)
			)
			(layer "F.Fab")
		)
		(fp_line
			(start -0.12065 0.2794)
			(end -0.12065 0.3048)
			(stroke
				(width 0.1)
				(type default)
			)
			(layer "F.Fab")
		)
		(fp_line
			(start 0.120396 0.2794)
			(end -0.12065 0.2794)
			(stroke
				(width 0.1)
				(type default)
			)
			(layer "F.Fab")
		)
		(fp_line
			(start -0.12065 -0.2794)
			(end 0.12065 -0.2794)
			(stroke
				(width 0.1)
				(type default)
			)
			(layer "F.Fab")
		)
		(fp_line
			(start 0.12065 -0.2794)
			(end 0.12065 -0.3048)
			(stroke
				(width 0.1)
				(type default)
			)
			(layer "F.Fab")
		)
		(fp_line
			(start 0.12065 -0.3048)
			(end 0.67945 -0.3048)
			(stroke
				(width 0.1)
				(type default)
			)
			(layer "F.Fab")
		)
		(fp_line
			(start 0.67945 -0.3048)
			(end 0.67945 0.3048)
			(stroke
				(width 0.1)
				(type default)
			)
			(layer "F.Fab")
		)
		(fp_line
			(start -0.67945 -0.305054)
			(end -0.12065 -0.305054)
			(stroke
				(width 0.1)
				(type default)
			)
			(layer "F.Fab")
		)
		(fp_line
			(start -0.12065 -0.305054)
			(end -0.12065 -0.2794)
			(stroke
				(width 0.1)
				(type default)
			)
			(layer "F.Fab")
		)
		(pad "1" smd circle
			(at -0.40005 0 270)
			(size 0 0)
			(layers "F.Cu" "F.Mask" "F.Paste")
			(net "H_CPU0_MEMTRIP_VT_N")
		)
		(pad "2" smd circle
			(at 0.40005 0 270)
			(size 0 0)
			(layers "F.Cu" "F.Mask" "F.Paste")
			(net "H_CPU0_MEMTRIP_LVC1_N")
		)
	)
	(footprint ""
		(layer "F.Cu")
		(at 437.242966 -120.614186)
		(property "Reference" "C626"
			(at 0 0 0)
			(layer "F.SilkS")
			(hide yes)
			(effects
				(font
					(size 1.27 1.27)
				)
			)
		)
		(property "Value" ""
			(at 0 0 0)
			(layer "F.Fab")
			(effects
				(font
					(size 1.27 1.27)
				)
			)
		)
		(duplicate_pad_numbers_are_jumpers no)
		(fp_line
			(start -0.7874 -0.4064)
			(end 0.7874 -0.4064)
			(stroke
				(width 0.1524)
				(type default)
			)
			(layer "F.SilkS")
		)
		(fp_line
			(start -0.7874 0.4064)
			(end -0.7874 -0.4064)
			(stroke
				(width 0.1524)
				(type default)
			)
			(layer "F.SilkS")
		)
		(fp_line
			(start 0.7874 -0.4064)
			(end 0.7874 0.4064)
			(stroke
				(width 0.1524)
				(type default)
			)
			(layer "F.SilkS")
		)
		(fp_line
			(start 0.7874 0.4064)
			(end -0.7874 0.4064)
			(stroke
				(width 0.1524)
				(type default)
			)
			(layer "F.SilkS")
		)
		(fp_line
			(start -0.67945 -0.305054)
			(end -0.12065 -0.305054)
			(stroke
				(width 0.1)
				(type default)
			)
			(layer "F.Fab")
		)
		(fp_line
			(start -0.67945 0.3048)
			(end -0.67945 -0.305054)
			(stroke
				(width 0.1)
				(type default)
			)
			(layer "F.Fab")
		)
		(fp_line
			(start -0.12065 -0.305054)
			(end -0.12065 -0.2794)
			(stroke
				(width 0.1)
				(type default)
			)
			(layer "F.Fab")
		)
		(fp_line
			(start -0.12065 -0.2794)
			(end 0.12065 -0.2794)
			(stroke
				(width 0.1)
				(type default)
			)
			(layer "F.Fab")
		)
		(fp_line
			(start -0.12065 0.2794)
			(end -0.12065 0.3048)
			(stroke
				(width 0.1)
				(type default)
			)
			(layer "F.Fab")
		)
		(fp_line
			(start -0.12065 0.3048)
			(end -0.67945 0.3048)
			(stroke
				(width 0.1)
				(type default)
			)
			(layer "F.Fab")
		)
		(fp_line
			(start 0.120396 0.2794)
			(end -0.12065 0.2794)
			(stroke
				(width 0.1)
				(type default)
			)
			(layer "F.Fab")
		)
		(fp_line
			(start 0.120396 0.3048)
			(end 0.120396 0.2794)
			(stroke
				(width 0.1)
				(type default)
			)
			(layer "F.Fab")
		)
		(fp_line
			(start 0.12065 -0.3048)
			(end 0.67945 -0.3048)
			(stroke
				(width 0.1)
				(type default)
			)
			(layer "F.Fab")
		)
		(fp_line
			(start 0.12065 -0.2794)
			(end 0.12065 -0.3048)
			(stroke
				(width 0.1)
				(type default)
			)
			(layer "F.Fab")
		)
		(fp_line
			(start 0.67945 -0.3048)
			(end 0.67945 0.3048)
			(stroke
				(width 0.1)
				(type default)
			)
			(layer "F.Fab")
		)
		(fp_line
			(start 0.67945 0.3048)
			(end 0.120396 0.3048)
			(stroke
				(width 0.1)
				(type default)
			)
			(layer "F.Fab")
		)
		(pad "1" smd circle
			(at -0.40005 0)
			(size 0 0)
			(layers "F.Cu" "F.Mask" "F.Paste")
			(net "PWRGD_PVCCD_HV_CPU0_R")
		)
		(pad "2" smd circle
			(at 0.40005 0)
			(size 0 0)
			(layers "F.Cu" "F.Mask" "F.Paste")
			(net "GND")
		)
	)
	(footprint ""
		(layer "F.Cu")
		(at 308.79288 -53.050948 90)
		(property "Reference" "R143"
			(at 0 0 90)
			(layer "F.SilkS")
			(hide yes)
			(effects
				(font
					(size 1.27 1.27)
				)
			)
		)
		(property "Value" ""
			(at 0 0 90)
			(layer "F.Fab")
			(effects
				(font
					(size 1.27 1.27)
				)
			)
		)
		(duplicate_pad_numbers_are_jumpers no)
		(fp_line
			(start 0.7874 -0.4064)
			(end 0.7874 0.4064)
			(stroke
				(width 0.1524)
				(type default)
			)
			(layer "F.SilkS")
		)
		(fp_line
			(start -0.7874 -0.4064)
			(end 0.7874 -0.4064)
			(stroke
				(width 0.1524)
				(type default)
			)
			(layer "F.SilkS")
		)
		(fp_line
			(start 0.7874 0.4064)
			(end -0.7874 0.4064)
			(stroke
				(width 0.1524)
				(type default)
			)
			(layer "F.SilkS")
		)
		(fp_line
			(start -0.7874 0.4064)
			(end -0.7874 -0.4064)
			(stroke
				(width 0.1524)
				(type default)
			)
			(layer "F.SilkS")
		)
		(fp_line
			(start -0.12065 -0.305054)
			(end -0.12065 -0.2794)
			(stroke
				(width 0.1)
				(type default)
			)
			(layer "F.Fab")
		)
		(fp_line
			(start -0.67945 -0.305054)
			(end -0.12065 -0.305054)
			(stroke
				(width 0.1)
				(type default)
			)
			(layer "F.Fab")
		)
		(fp_line
			(start 0.67945 -0.3048)
			(end 0.67945 0.3048)
			(stroke
				(width 0.1)
				(type default)
			)
			(layer "F.Fab")
		)
		(fp_line
			(start 0.12065 -0.3048)
			(end 0.67945 -0.3048)
			(stroke
				(width 0.1)
				(type default)
			)
			(layer "F.Fab")
		)
		(fp_line
			(start 0.12065 -0.2794)
			(end 0.12065 -0.3048)
			(stroke
				(width 0.1)
				(type default)
			)
			(layer "F.Fab")
		)
		(fp_line
			(start -0.12065 -0.2794)
			(end 0.12065 -0.2794)
			(stroke
				(width 0.1)
				(type default)
			)
			(layer "F.Fab")
		)
		(fp_line
			(start 0.120396 0.2794)
			(end -0.12065 0.2794)
			(stroke
				(width 0.1)
				(type default)
			)
			(layer "F.Fab")
		)
		(fp_line
			(start -0.12065 0.2794)
			(end -0.12065 0.3048)
			(stroke
				(width 0.1)
				(type default)
			)
			(layer "F.Fab")
		)
		(fp_line
			(start 0.67945 0.3048)
			(end 0.120396 0.3048)
			(stroke
				(width 0.1)
				(type default)
			)
			(layer "F.Fab")
		)
		(fp_line
			(start 0.120396 0.3048)
			(end 0.120396 0.2794)
			(stroke
				(width 0.1)
				(type default)
			)
			(layer "F.Fab")
		)
		(fp_line
			(start -0.12065 0.3048)
			(end -0.67945 0.3048)
			(stroke
				(width 0.1)
				(type default)
			)
			(layer "F.Fab")
		)
		(fp_line
			(start -0.67945 0.3048)
			(end -0.67945 -0.305054)
			(stroke
				(width 0.1)
				(type default)
			)
			(layer "F.Fab")
		)
		(pad "1" smd circle
			(at -0.40005 0 90)
			(size 0 0)
			(layers "F.Cu" "F.Mask" "F.Paste")
			(net "PECI_PCH")
		)
		(pad "2" smd circle
			(at 0.40005 0 90)
			(size 0 0)
			(layers "F.Cu" "F.Mask" "F.Paste")
			(net "PECI_PCH_R")
		)
	)
	(footprint ""
		(layer "F.Cu")
		(at 438.87771 -43.960288 180)
		(property "Reference" "R3241"
			(at 0 0 180)
			(layer "F.SilkS")
			(hide yes)
			(effects
				(font
					(size 1.27 1.27)
				)
			)
		)
		(property "Value" ""
			(at 0 0 180)
			(layer "F.Fab")
			(effects
				(font
					(size 1.27 1.27)
				)
			)
		)
		(duplicate_pad_numbers_are_jumpers no)
		(fp_line
			(start 0.7874 0.4064)
			(end -0.7874 0.4064)
			(stroke
				(width 0.1524)
				(type default)
			)
			(layer "F.SilkS")
		)
		(fp_line
			(start 0.7874 -0.4064)
			(end 0.7874 0.4064)
			(stroke
				(width 0.1524)
				(type default)
			)
			(layer "F.SilkS")
		)
		(fp_line
			(start -0.7874 0.4064)
			(end -0.7874 -0.4064)
			(stroke
				(width 0.1524)
				(type default)
			)
			(layer "F.SilkS")
		)
		(fp_line
			(start -0.7874 -0.4064)
			(end 0.7874 -0.4064)
			(stroke
				(width 0.1524)
				(type default)
			)
			(layer "F.SilkS")
		)
		(fp_line
			(start 0.67945 0.3048)
			(end 0.120396 0.3048)
			(stroke
				(width 0.1)
				(type default)
			)
			(layer "F.Fab")
		)
		(fp_line
			(start 0.67945 -0.3048)
			(end 0.67945 0.3048)
			(stroke
				(width 0.1)
				(type default)
			)
			(layer "F.Fab")
		)
		(fp_line
			(start 0.12065 -0.2794)
			(end 0.12065 -0.3048)
			(stroke
				(width 0.1)
				(type default)
			)
			(layer "F.Fab")
		)
		(fp_line
			(start 0.12065 -0.3048)
			(end 0.67945 -0.3048)
			(stroke
				(width 0.1)
				(type default)
			)
			(layer "F.Fab")
		)
		(fp_line
			(start 0.120396 0.3048)
			(end 0.120396 0.2794)
			(stroke
				(width 0.1)
				(type default)
			)
			(layer "F.Fab")
		)
		(fp_line
			(start 0.120396 0.2794)
			(end -0.12065 0.2794)
			(stroke
				(width 0.1)
				(type default)
			)
			(layer "F.Fab")
		)
		(fp_line
			(start -0.12065 0.3048)
			(end -0.67945 0.3048)
			(stroke
				(width 0.1)
				(type default)
			)
			(layer "F.Fab")
		)
		(fp_line
			(start -0.12065 0.2794)
			(end -0.12065 0.3048)
			(stroke
				(width 0.1)
				(type default)
			)
			(layer "F.Fab")
		)
		(fp_line
			(start -0.12065 -0.2794)
			(end 0.12065 -0.2794)
			(stroke
				(width 0.1)
				(type default)
			)
			(layer "F.Fab")
		)
		(fp_line
			(start -0.12065 -0.305054)
			(end -0.12065 -0.2794)
			(stroke
				(width 0.1)
				(type default)
			)
			(layer "F.Fab")
		)
		(fp_line
			(start -0.67945 0.3048)
			(end -0.67945 -0.305054)
			(stroke
				(width 0.1)
				(type default)
			)
			(layer "F.Fab")
		)
		(fp_line
			(start -0.67945 -0.305054)
			(end -0.12065 -0.305054)
			(stroke
				(width 0.1)
				(type default)
			)
			(layer "F.Fab")
		)
		(pad "1" smd circle
			(at -0.40005 0 180)
			(size 0 0)
			(layers "F.Cu" "F.Mask" "F.Paste")
			(net "SMB_OCP_SFF_3V3AUX_SDA")
		)
		(pad "2" smd circle
			(at 0.40005 0 180)
			(size 0 0)
			(layers "F.Cu" "F.Mask" "F.Paste")
			(net "P3V3_AUX")
		)
	)
	(footprint ""
		(layer "F.Cu")
		(at 117.526816 -256.6543 -90)
		(property "Reference" "C285"
			(at 0 0 270)
			(layer "F.SilkS")
			(hide yes)
			(effects
				(font
					(size 1.27 1.27)
				)
			)
		)
		(property "Value" ""
			(at 0 0 270)
			(layer "F.Fab")
			(effects
				(font
					(size 1.27 1.27)
				)
			)
		)
		(duplicate_pad_numbers_are_jumpers no)
		(fp_line
			(start -0.7874 0.4064)
			(end -0.7874 -0.4064)
			(stroke
				(width 0.1524)
				(type default)
			)
			(layer "F.SilkS")
		)
		(fp_line
			(start 0.7874 0.4064)
			(end -0.7874 0.4064)
			(stroke
				(width 0.1524)
				(type default)
			)
			(layer "F.SilkS")
		)
		(fp_line
			(start -0.7874 -0.4064)
			(end 0.7874 -0.4064)
			(stroke
				(width 0.1524)
				(type default)
			)
			(layer "F.SilkS")
		)
		(fp_line
			(start 0.7874 -0.4064)
			(end 0.7874 0.4064)
			(stroke
				(width 0.1524)
				(type default)
			)
			(layer "F.SilkS")
		)
		(fp_line
			(start -0.67945 0.3048)
			(end -0.67945 -0.305054)
			(stroke
				(width 0.1)
				(type default)
			)
			(layer "F.Fab")
		)
		(fp_line
			(start -0.12065 0.3048)
			(end -0.67945 0.3048)
			(stroke
				(width 0.1)
				(type default)
			)
			(layer "F.Fab")
		)
		(fp_line
			(start 0.120396 0.3048)
			(end 0.120396 0.2794)
			(stroke
				(width 0.1)
				(type default)
			)
			(layer "F.Fab")
		)
		(fp_line
			(start 0.67945 0.3048)
			(end 0.120396 0.3048)
			(stroke
				(width 0.1)
				(type default)
			)
			(layer "F.Fab")
		)
		(fp_line
			(start -0.12065 0.2794)
			(end -0.12065 0.3048)
			(stroke
				(width 0.1)
				(type default)
			)
			(layer "F.Fab")
		)
		(fp_line
			(start 0.120396 0.2794)
			(end -0.12065 0.2794)
			(stroke
				(width 0.1)
				(type default)
			)
			(layer "F.Fab")
		)
		(fp_line
			(start -0.12065 -0.2794)
			(end 0.12065 -0.2794)
			(stroke
				(width 0.1)
				(type default)
			)
			(layer "F.Fab")
		)
		(fp_line
			(start 0.12065 -0.2794)
			(end 0.12065 -0.3048)
			(stroke
				(width 0.1)
				(type default)
			)
			(layer "F.Fab")
		)
		(fp_line
			(start 0.12065 -0.3048)
			(end 0.67945 -0.3048)
			(stroke
				(width 0.1)
				(type default)
			)
			(layer "F.Fab")
		)
		(fp_line
			(start 0.67945 -0.3048)
			(end 0.67945 0.3048)
			(stroke
				(width 0.1)
				(type default)
			)
			(layer "F.Fab")
		)
		(fp_line
			(start -0.67945 -0.305054)
			(end -0.12065 -0.305054)
			(stroke
				(width 0.1)
				(type default)
			)
			(layer "F.Fab")
		)
		(fp_line
			(start -0.12065 -0.305054)
			(end -0.12065 -0.2794)
			(stroke
				(width 0.1)
				(type default)
			)
			(layer "F.Fab")
		)
		(pad "1" smd circle
			(at -0.40005 0 270)
			(size 0 0)
			(layers "F.Cu" "F.Mask" "F.Paste")
			(net "PVCCIN_CPU1")
		)
		(pad "2" smd circle
			(at 0.40005 0 270)
			(size 0 0)
			(layers "F.Cu" "F.Mask" "F.Paste")
			(net "GND")
		)
	)
	(footprint ""
		(layer "F.Cu")
		(at 382.84785 -408.517344 -90)
		(property "Reference" "C877"
			(at 0 0 270)
			(layer "F.SilkS")
			(hide yes)
			(effects
				(font
					(size 1.27 1.27)
				)
			)
		)
		(property "Value" ""
			(at 0 0 270)
			(layer "F.Fab")
			(effects
				(font
					(size 1.27 1.27)
				)
			)
		)
		(duplicate_pad_numbers_are_jumpers no)
		(fp_line
			(start -0.299974 0.150114)
			(end -0.299974 -0.150114)
			(stroke
				(width 0.1)
				(type default)
			)
			(layer "F.Fab")
		)
		(fp_line
			(start 0.299974 0.150114)
			(end -0.299974 0.150114)
			(stroke
				(width 0.1)
				(type default)
			)
			(layer "F.Fab")
		)
		(fp_line
			(start -0.299974 -0.150114)
			(end 0.299974 -0.150114)
			(stroke
				(width 0.1)
				(type default)
			)
			(layer "F.Fab")
		)
		(fp_line
			(start 0.299974 -0.150114)
			(end 0.299974 0.150114)
			(stroke
				(width 0.1)
				(type default)
			)
			(layer "F.Fab")
		)
		(pad "1" smd rect
			(at -0.2667 0 270)
			(size 0.3048 0.381)
			(layers "F.Cu" "F.Mask" "F.Paste")
			(net "P5E_CPU0_PE3_TX_C_DP<12>")
		)
		(pad "2" smd rect
			(at 0.2667 0 270)
			(size 0.3048 0.381)
			(layers "F.Cu" "F.Mask" "F.Paste")
			(net "P5E_CPU0_PE3_TX_DP<12>")
		)
	)
	(footprint ""
		(layer "F.Cu")
		(at 89.535 -32.070548)
		(property "Reference" "U321"
			(at -2.2606 -2.352548 0)
			(unlocked yes)
			(layer "F.SilkS")
			(effects
				(font
					(size 0.7874 0.5842)
					(thickness 0.1524)
				)
				(justify left)
			)
		)
		(property "Value" ""
			(at 0 0 0)
			(layer "F.Fab")
			(effects
				(font
					(size 1.27 1.27)
				)
			)
		)
		(duplicate_pad_numbers_are_jumpers no)
		(fp_line
			(start -2.032 -1.549908)
			(end 2.032 -1.549908)
			(stroke
				(width 0.1524)
				(type default)
			)
			(layer "F.SilkS")
		)
		(fp_line
			(start -2.032 1.549908)
			(end -2.032 -1.549908)
			(stroke
				(width 0.1524)
				(type default)
			)
			(layer "F.SilkS")
		)
		(fp_line
			(start 2.032 -1.549908)
			(end 2.032 1.549908)
			(stroke
				(width 0.1524)
				(type default)
			)
			(layer "F.SilkS")
		)
		(fp_line
			(start 2.032 1.549908)
			(end -2.032 1.549908)
			(stroke
				(width 0.1524)
				(type default)
			)
			(layer "F.SilkS")
		)
		(fp_poly
			(pts
				(xy -2.9464 -1.2192) (xy -2.9464 -0.7112) (xy -2.1844 -0.9652)
			)
			(stroke
				(width 0)
				(type default)
			)
			(fill yes)
			(layer "F.SilkS")
		)
		(fp_line
			(start -0.849884 -1.549908)
			(end -0.849884 1.549908)
			(stroke
				(width 0.1)
				(type default)
			)
			(layer "F.Fab")
		)
		(fp_line
			(start -0.849884 1.549908)
			(end 0.849884 1.549908)
			(stroke
				(width 0.1)
				(type default)
			)
			(layer "F.Fab")
		)
		(fp_line
			(start 0.849884 -1.549908)
			(end -0.849884 -1.549908)
			(stroke
				(width 0.1)
				(type default)
			)
			(layer "F.Fab")
		)
		(fp_line
			(start 0.849884 1.549908)
			(end 0.849884 -1.549908)
			(stroke
				(width 0.1)
				(type default)
			)
			(layer "F.Fab")
		)
		(fp_poly
			(pts
				(xy -2.9464 -1.2192) (xy -2.9464 -0.7112) (xy -2.1844 -0.9652)
			)
			(stroke
				(width 0)
				(type default)
			)
			(fill yes)
			(layer "F.Fab")
		)
		(pad "1" smd rect
			(at -1.225042 -0.94996 270)
			(size 0.4572 1.3208)
			(layers "F.Cu" "F.Mask" "F.Paste")
			(net "CLK_50M_NCSI_OCP_V3_2")
		)
		(pad "2" smd rect
			(at -1.225042 0 270)
			(size 0.4572 1.3208)
			(layers "F.Cu" "F.Mask" "F.Paste")
			(net "CLK_50M_NCSI_OCP_V3_2_ISO_R")
		)
		(pad "3" smd rect
			(at -1.225042 0.94996 270)
			(size 0.4572 1.3208)
			(layers "F.Cu" "F.Mask" "F.Paste")
			(net "GND")
		)
		(pad "4" smd rect
			(at 1.225042 0.94996 270)
			(size 0.4572 1.3208)
			(layers "F.Cu" "F.Mask" "F.Paste")
			(net "FB_BMC_ISOLATE1")
		)
		(pad "5" smd rect
			(at 1.225042 -0.94996 270)
			(size 0.4572 1.3208)
			(layers "F.Cu" "F.Mask" "F.Paste")
			(net "P3V3_AUX")
		)
	)
)
